FILE_TYPE = CONNECTIVITY;
{Allegro Design Entry HDL 17.4-2019 S026 (4007227) 1/17/2022}
"PAGE_NUMBER" = 346;
0"NC";
1"GND\g";
2"GND\g";
3"GND\g";
4"GND\g";
5"P3V3_AUX\g";
6"P1V8_AUX\g";
7"GND\g"VOLTAGE"0";
8"P1V8_AUX\g";
9"P3V3_AUX\g";
10"GND\g";
11"P3V3_E1S_0\g";
12"P3V3_E1S_0\g";
13"SMB_M2_P1_1V8AUX_SDA"CDS_PHYS_NET_NAME"SMB_SENSOR_M2_P0_3V3AUX_SCL";
14"SMB_M2_P1_1V8AUX_SCL"CDS_PHYS_NET_NAME"SMB_SENSOR_M2_P0_3V3AUX_SDA";
15"PWRGD_P1V8_AUX_R"CDS_PHYS_NET_NAME"SMB_SENSOR_M2_P0_3V3AUX_SDA";
16"SMB_M2_P1_1V8AUX_SDA_R"CDS_PHYS_NET_NAME"SMB_SENSOR_M2_P0_3V3AUX_SCL";
17"SMB_M2_P1_1V8AUX_SCL_R"CDS_PHYS_NET_NAME"SMB_SENSOR_M2_P0_3V3AUX_SDA";
18"SMB_PCIE_M2_0_EN"CDS_PHYS_NET_NAME"SMB_SENSOR_M2_P0_3V3AUX_SDA";
19"SMB_SENSOR_M2_P1_3V3AUX_SDA"CDS_PHYS_NET_NAME"SMB_SENSOR_M2_P0_3V3AUX_SCL";
20"SMB_SENSOR_M2_P1_3V3AUX_SCL"CDS_PHYS_NET_NAME"SMB_SENSOR_M2_P0_3V3AUX_SDA";
21"SMB_E1S_3V3AUX_ISO_SDA_R"CDS_PHYS_NET_NAME"SMB_SENSOR_M2_P0_3V3AUX_SDA";
22"SMB_PCIE_E1S_ISO_EN_R"CDS_PHYS_NET_NAME"SMB_PCIE_M2_1_EN";
23"SMB_E1S_3V3AUX_ISO_SCL_R"CDS_PHYS_NET_NAME"SMB_SENSOR_M2_P0_3V3AUX_SCL";
24"SMB_SENSOR_E1S_3V3AUX_SDA"CDS_PHYS_NET_NAME"SMB_SENSOR_M2_P0_3V3AUX_SCL";
25"SMB_SENSOR_E1S_3V3AUX_SCL"CDS_PHYS_NET_NAME"SMB_SENSOR_M2_P0_3V3AUX_SDA";
26"SMB_E1S_3V3AUX_ISO_SCL"CDS_PHYS_NET_NAME"SMB_SENSOR_M2_P0_3V3AUX_SCL";
27"SMB_E1S_3V3AUX_ISO_SDA"CDS_PHYS_NET_NAME"SMB_SENSOR_M2_P0_3V3AUX_SDA";
28"SMB_PCIE_E1S_ISO_EN"CDS_PHYS_NET_NAME"PWRGD_P1V8_PCH_AUX";
%"PCA9306DP1"
"1","(725,3400)","2","pure_quanta","I27";
;
LOCATION"U98"
$SEC"1"
CDS_SEC"1"
MATERIAL"IC"
VALUE"PCA9306DP1"
PART_TYPE"SMLF"
PART_NUMBER"AL009306K04"
CDS_LMAN_SYM_OUTLINE"-200,175,200,-175"
NEEDS_NO_SIZE"TRUE"
CDS_LIB"pure_quanta";
"GND"
$PN"1"7;
"EN"
$PN"8"18;
"VREF2"
$PN"7"18;
"SCL2"
$PN"6"20;
"SDA2"
$PN"5"19;
"SDA1"
$PN"4"16;
"SCL1"
$PN"3"17;
"VREF1"
$PN"2"6;
%"Q_CAP"
"1","(1400,3800)","0","pure_quanta","I28";
;
LOCATION"C1323"
$SEC"1"
CDS_SEC"1"
MATERIAL"X7R"
PACK_TYPE"0402"
TOLERANCE"10%"
VOLTAGE"25V"
VALUE"0.1UF"
PART_NUMBER"CH4104K1B00"
CDS_LIB"pure_quanta";
"B"
$PN"2"1;
"A"
$PN"1"6;
%"UNIVERSAL_POWER"
"1","(1225,4100)","0","pure_quanta_power","I29";
;
HDL_POWER"P1V8_AUX"
CDS_LIB"pure_quanta_power";
"A"6;
%"UNIVERSAL_GND"
"1","(1400,3575)","0","pure_quanta_power","I30";
;
HDL_POWER"GND"
CDS_LIB"pure_quanta_power";
"A"1;
%"UNIVERSAL_GND"
"1","(350,3150)","0","pure_quanta_power","I38";
;
HDL_POWER"GND"
CDS_LIB"pure_quanta_power";
"A"7;
%"Q_RES"
"2","(2250,3775)","0","pure_quanta","I43";
;
LOCATION"R1702"
$SEC"1"
CDS_SEC"1"
PACK_TYPE"0402LF"
VALUE"4.7K"
TOLERANCE"5%"
MATERIAL"CHIP"
WATTAGE"1/16W"
PART_NUMBER"CS24702JB10"
CDS_LIB"pure_quanta";
"A"
$PN"1"8;
"B"
$PN"2"16;
%"Q_RES"
"2","(2500,3775)","0","pure_quanta","I45";
;
LOCATION"R1703"
$SEC"1"
CDS_SEC"1"
PACK_TYPE"0402LF"
MATERIAL"CHIP"
TOLERANCE"5%"
VALUE"4.7K"
WATTAGE"1/16W"
PART_NUMBER"CS24702JB10"
CDS_LIB"pure_quanta";
"A"
$PN"1"8;
"B"
$PN"2"17;
%"UNIVERSAL_POWER"
"1","(2250,4100)","0","pure_quanta_power","I47";
;
HDL_POWER"P1V8_AUX"
CDS_LIB"pure_quanta_power";
"A"8;
%"UNIVERSAL_POWER"
"1","(0,4125)","0","pure_quanta_power","I51";
;
HDL_POWER"P3V3_AUX"
CDS_LIB"pure_quanta_power";
"A"9;
%"Q_CAP"
"1","(-425,3775)","2","pure_quanta","I52";
;
LOCATION"C1305"
$SEC"1"
CDS_SEC"1"
TOLERANCE"10%"
VALUE"0.1UF"
VOLTAGE"25V"
MATERIAL"X7R"
PACK_TYPE"0402"
PART_NUMBER"CH4104K1B00"
CDS_LIB"pure_quanta";
"B"
$PN"2"2;
"A"
$PN"1"9;
%"UNIVERSAL_GND"
"1","(-425,3575)","0","pure_quanta_power","I53";
;
HDL_POWER"GND"
CDS_LIB"pure_quanta_power";
"A"2;
%"Q_RES"
"1","(2800,3425)","0","pure_quanta","I65";
;
LOCATION"R2410"
$SEC"1"
CDS_SEC"1"
WATTAGE"1/16W"
MATERIAL"CHIP"
VALUE"33.2"
PACK_TYPE"0402LF"
TOLERANCE"1%"
PART_NUMBER"CS03322FB03"
CDS_LIB"pure_quanta";
"B"
$PN"2"13;
"A"
$PN"1"16;
%"Q_RES"
"1","(2800,3375)","0","pure_quanta","I66";
;
LOCATION"R2411"
$SEC"1"
CDS_SEC"1"
MATERIAL"CHIP"
VALUE"33.2"
TOLERANCE"1%"
PART_NUMBER"CS03322FB03"
CDS_LIB"pure_quanta"
PACK_TYPE"0402LF"
WATTAGE"1/16W";
"B"
$PN"2"14;
"A"
$PN"1"17;
%"Q_RES"
"1","(2300,3100)","0","pure_quanta","I70";
;
LOCATION"R2476"
$SEC"1"
CDS_SEC"1"
MATERIAL"EMPTY"
WATTAGE"1/16W"
PACK_TYPE"0402LF"
TOLERANCE"1%"
VALUE"200K"
PART_NUMBER"CS42002FB05"
CDS_LIB"pure_quanta";
"B"
$PN"2"15;
"A"
$PN"1"18;
%"Q_RES"
"2","(0,3750)","0","pure_quanta","I72";
;
LOCATION"R1700"
$SEC"1"
CDS_SEC"1"
TOLERANCE"1%"
PACK_TYPE"0402LF"
WATTAGE"1/16W"
VALUE"200K"
MATERIAL"CHIP"
PART_NUMBER"CS42002FB05"
CDS_LIB"pure_quanta";
"A"
$PN"1"9;
"B"
$PN"2"18;
%"Q_RES"
"1","(2700,1225)","0","pure_quanta","I76";
;
LOCATION"R3533"
$SEC"1"
CDS_SEC"1"
MATERIAL"CHIP"
WATTAGE"1/16W"
PACK_TYPE"0402LF"
VALUE"33.2"
TOLERANCE"1%"
PART_NUMBER"CS03322FB03"
CDS_LIB"pure_quanta";
"B"
$PN"2"26;
"A"
$PN"1"23;
%"Q_RES"
"1","(2700,1125)","0","pure_quanta","I77";
;
LOCATION"R3534"
$SEC"1"
CDS_SEC"1"
TOLERANCE"1%"
VALUE"33.2"
MATERIAL"CHIP"
PART_NUMBER"CS03322FB03"
WATTAGE"1/16W"
PACK_TYPE"0402LF"
CDS_LIB"pure_quanta";
"B"
$PN"2"27;
"A"
$PN"1"21;
%"Q_RES"
"2","(2375,1575)","0","pure_quanta","I78";
;
LOCATION"R3532"
$SEC"1"
CDS_SEC"1"
VALUE"4.7K"
TOLERANCE"5%"
PACK_TYPE"0402LF"
WATTAGE"1/16W"
MATERIAL"CHIP"
PART_NUMBER"CS24702JB10"
CDS_LIB"pure_quanta";
"A"
$PN"1"12;
"B"
$PN"2"21;
%"Q_RES"
"2","(2125,1575)","0","pure_quanta","I80";
;
LOCATION"R3530"
$SEC"1"
CDS_SEC"1"
VALUE"4.7K"
MATERIAL"CHIP"
PACK_TYPE"0402LF"
TOLERANCE"5%"
WATTAGE"1/16W"
PART_NUMBER"CS24702JB10"
CDS_LIB"pure_quanta";
"A"
$PN"1"12;
"B"
$PN"2"23;
%"Q_CAP"
"1","(1600,1650)","0","pure_quanta","I82";
;
LOCATION"C1998"
$SEC"1"
CDS_SEC"1"
PACK_TYPE"0402"
VOLTAGE"25V"
MATERIAL"X7R"
TOLERANCE"10%"
VALUE"0.1UF"
PART_NUMBER"CH4104K1B00"
CDS_LIB"pure_quanta";
"B"
$PN"2"3;
"A"
$PN"1"11;
%"UNIVERSAL_GND"
"1","(1600,1425)","0","pure_quanta_power","I84";
;
HDL_POWER"GND"
CDS_LIB"pure_quanta_power";
"A"3;
%"UNIVERSAL_POWER"
"1","(75,1975)","0","pure_quanta_power","I87";
;
HDL_POWER"P3V3_AUX"
CDS_LIB"pure_quanta_power";
"A"5;
%"Q_CAP"
"1","(-350,1625)","2","pure_quanta","I89";
;
LOCATION"C1997"
$SEC"1"
CDS_SEC"1"
PACK_TYPE"0402"
VOLTAGE"25V"
VALUE"0.1UF"
TOLERANCE"10%"
MATERIAL"X7R"
PART_NUMBER"CH4104K1B00"
CDS_LIB"pure_quanta";
"B"
$PN"2"4;
"A"
$PN"1"5;
%"UNIVERSAL_GND"
"1","(-350,1425)","0","pure_quanta_power","I90";
;
HDL_POWER"GND"
CDS_LIB"pure_quanta_power";
"A"4;
%"PCA9617ADP"
"1","(850,1175)","2","pure_quanta","I93";
;
LOCATION"U279"
$SEC"1"
CDS_SEC"1"
MATERIAL"IC"
PART_TYPE"SMLF"
VALUE"PCA9617ADP"
PART_NUMBER"AL009617K02"
NEEDS_NO_SIZE"TRUE"
CDS_LMAN_SYM_OUTLINE"-275,300,275,-300"
CDS_LIB"pure_quanta";
"GND"
$PN"4"10;
"SCLB"
$PN"7"25;
"SDAB"
$PN"6"24;
"SDAA"
$PN"3"21;
"SCLA"
$PN"2"23;
"VCCB"
$PN"8"5;
"VCCA"
$PN"1"11;
"EN"
$PN"5"22;
%"UNIVERSAL_GND"
"1","(1450,850)","0","pure_quanta_power","I95";
;
HDL_POWER"GND"
CDS_LIB"pure_quanta_power";
"A"10;
%"Q_RES"
"1","(-1500,975)","0","pure_quanta","I96";
;
LOCATION"R3531"
$SEC"1"
CDS_SEC"1"
MATERIAL"EMPTY"
TOLERANCE"1%"
VALUE"200K"
WATTAGE"1/16W"
PACK_TYPE"0402LF"
PART_NUMBER"CS42002FB05"
CDS_LIB"pure_quanta";
"B"
$PN"2"22;
"A"
$PN"1"28;
%"UNIVERSAL_POWER"
"1","(1425,1950)","0","pure_quanta_power","I97";
;
HDL_POWER"P3V3_E1S_0"
CDS_LIB"pure_quanta_power";
"A"11;
%"UNIVERSAL_POWER"
"1","(2125,1900)","0","pure_quanta_power","I98";
;
HDL_POWER"P3V3_E1S_0"
CDS_LIB"pure_quanta_power";
"A"12;
%"Q_RES"
"2","(-25,1600)","0","pure_quanta","I99";
;
LOCATION"R3529"
$SEC"1"
CDS_SEC"1"
TOLERANCE"1%"
PACK_TYPE"0402LF"
MATERIAL"CHIP"
WATTAGE"1/16W"
VALUE"10K"
PART_NUMBER"CS31002FB08"
CDS_LIB"pure_quanta";
"A"
$PN"1"5;
"B"
$PN"2"22;
END.
